# SCM (Grand Teton) — schematic netlist excerpt (pin names and nets, part order shuffled) for the footprints in the layout excerpt that follows; sources: Cadence DE-HDL packaged netlist, KiCad conversion of 12092022_DA0F0TMDCD0_F0T_Management_Board_D_brd_V3_OCP.brd

J19  PICOPROBE_BXA  DELTA-L 4.0 EMPTY  pkg TRIANG_LAUNCH_3PXB  page 58
  \1_p\  = 85_5INCH_IN4_DP
  \2_n\  = 85_5INCH_IN4_DN
  \3_g\  = GND_P1

(kicad_pcb
	(version 20260206)
	(generator "pcbnew")
	(generator_version "10.0")
	(general
		(thickness 1.6)
		(legacy_teardrops no)
	)
	(paper "A4")
	(title_block
		(title "12092022_DA0F0TMDCD0_F0T_Management_Board_D_brd_V3_OCP.brd")
		(comment 1 "Grand Teton / footprints 613-613 of 1440")
	)
	(layers
		(0 "F.Cu" signal "TOP")
		(4 "In1.Cu" signal "GND")
		(6 "In2.Cu" signal "IN1")
		(8 "In3.Cu" signal "GND1")
		(10 "In4.Cu" signal "IN2")
		(12 "In5.Cu" signal "VCC")
		(14 "In6.Cu" signal "VCC1")
		(16 "In7.Cu" signal "IN3")
		(18 "In8.Cu" signal "GND2")
		(20 "In9.Cu" signal "IN4")
		(22 "In10.Cu" signal "GND3")
		(2 "B.Cu" signal "BOTTOM")
		(9 "F.Adhes" user "F.Adhesive")
		(11 "B.Adhes" user "B.Adhesive")
		(13 "F.Paste" user "Package Geometry/Pastemask Top")
		(15 "B.Paste" user "Package Geometry/Pastemask Bottom")
		(5 "F.SilkS" user "Ref Des/Silkscreen Top")
		(7 "B.SilkS" user "Ref Des/Silkscreen Bottom")
		(1 "F.Mask" user "Board Geometry/Soldermask Top")
		(3 "B.Mask" user "Board Geometry/Soldermask Bottom")
		(17 "Dwgs.User" user "User.Drawings")
		(19 "Cmts.User" user "User.Comments")
		(21 "Eco1.User" user "User.Eco1")
		(23 "Eco2.User" user "User.Eco2")
		(25 "Edge.Cuts" user "Board Geometry/Outline")
		(27 "Margin" user)
		(31 "F.CrtYd" user "Package Geometry/Place Bound Top")
		(29 "B.CrtYd" user "Package Geometry/Place Bound Bottom")
		(35 "F.Fab" user "Ref Des/Assembly Top")
		(33 "B.Fab" user "Ref Des/Assembly Bottom")
	)
	(footprint ""
		(layer "F.Cu")
		(at 95.926656 -4.605274 -90)
		(property "Reference" "J19"
			(at 1.049274 -2.779014 90)
			(unlocked yes)
			(layer "F.SilkS")
			(effects
				(font
					(size 0.7874 0.5842)
					(thickness 0.1524)
				)
				(justify left)
			)
		)
		(property "Value" ""
			(at 0 0 270)
			(layer "F.Fab")
			(effects
				(font
					(size 1.27 1.27)
				)
			)
		)
		(duplicate_pad_numbers_are_jumpers no)
		(fp_line
			(start -1.2192 2.1082)
			(end -1.2192 -2.1082)
			(stroke
				(width 0.1524)
				(type default)
			)
			(layer "F.SilkS")
		)
		(fp_line
			(start 1.2192 2.1082)
			(end -1.2192 2.1082)
			(stroke
				(width 0.1524)
				(type default)
			)
			(layer "F.SilkS")
		)
		(fp_line
			(start 1.2192 0.810514)
			(end 1.2192 2.1082)
			(stroke
				(width 0.1524)
				(type default)
			)
			(layer "F.SilkS")
		)
		(fp_line
			(start -1.2192 -2.1082)
			(end 1.2192 -2.1082)
			(stroke
				(width 0.1524)
				(type default)
			)
			(layer "F.SilkS")
		)
		(fp_line
			(start 1.2192 -2.1082)
			(end 1.2192 -0.825246)
			(stroke
				(width 0.1524)
				(type default)
			)
			(layer "F.SilkS")
		)
		(pad "" np_thru_hole circle
			(at -2.8829 -1.27 180)
			(size 1.0414 1.0414)
			(drill 1.0414)
			(layers "*.Cu" "*.Mask")
			(clearance 0.381)
			(thermal_gap 0.381)
		)
		(pad "" np_thru_hole circle
			(at -2.8829 1.27 180)
			(size 1.0414 1.0414)
			(drill 1.0414)
			(layers "*.Cu" "*.Mask")
			(clearance 0.381)
			(thermal_gap 0.381)
		)
		(pad "" np_thru_hole circle
			(at 3.4671 -1.27 180)
			(size 1.0414 1.0414)
			(drill 1.0414)
			(layers "*.Cu" "*.Mask")
			(clearance 0.381)
			(thermal_gap 0.381)
		)
		(pad "" np_thru_hole circle
			(at 3.4671 1.27 180)
			(size 1.0414 1.0414)
			(drill 1.0414)
			(layers "*.Cu" "*.Mask")
			(clearance 0.381)
			(thermal_gap 0.381)
		)
		(pad "1" smd rect
			(at 0.8255 -0.249936 180)
			(size 0.3048 0.508)
			(layers "F.Cu" "F.Mask" "F.Paste")
			(net "85_5INCH_IN4_DP")
		)
		(pad "2" smd rect
			(at 0.8255 0.249936 180)
			(size 0.3048 0.508)
			(layers "F.Cu" "F.Mask" "F.Paste")
			(net "85_5INCH_IN4_DN")
		)
		(pad "3" smd circle
			(at 0 0 270)
			(size 0 0)
			(layers "F.Cu" "F.Mask" "F.Paste")
			(net "GND_P1")
		)
		(zone
			(layer "F.Cu")
			(hatch none 0.5)
			(connect_pads
				(clearance 0)
			)
			(min_thickness 0.25)
			(keepout
				(tracks not_allowed)
				(vias allowed)
				(pads allowed)
				(copperpour not_allowed)
				(footprints allowed)
			)
			(placement
				(enabled no)
				(sheetname "")
			)
			(fill
				(thermal_gap 0.5)
				(thermal_bridge_width 0.5)
				(island_removal_mode 0)
			)
			(polygon
				(pts
					(xy 96.475296 -3.487674) (xy 96.379792 -3.487674) (xy 96.379792 -4.084574) (xy 95.973392 -4.084574)
					(xy 95.973392 -3.487674) (xy 95.87992 -3.487674) (xy 95.87992 -4.084574) (xy 95.47352 -4.084574)
					(xy 95.47352 -3.487674) (xy 95.378016 -3.487674) (xy 95.378016 -4.186174) (xy 96.475296 -4.186174)
				)
			)
		)
		(zone
			(layers "F.Cu" "B.Cu" "In1.Cu" "In2.Cu" "In3.Cu" "In4.Cu" "In5.Cu" "In6.Cu"
				"In7.Cu" "In8.Cu" "In9.Cu" "In10.Cu"
			)
			(hatch none 0.5)
			(connect_pads
				(clearance 0)
			)
			(min_thickness 0.25)
			(keepout
				(tracks not_allowed)
				(vias allowed)
				(pads allowed)
				(copperpour not_allowed)
				(footprints allowed)
			)
			(placement
				(enabled no)
				(sheetname "")
			)
			(fill
				(thermal_gap 0.5)
				(thermal_bridge_width 0.5)
				(island_removal_mode 0)
			)
			(polygon
				(pts
					(arc
						(start 95.583756 -7.488174)
						(mid 93.729556 -7.488174)
						(end 95.583756 -7.488174)
					)
				)
			)
		)
		(zone
			(layers "F.Cu" "B.Cu" "In1.Cu" "In2.Cu" "In3.Cu" "In4.Cu" "In5.Cu" "In6.Cu"
				"In7.Cu" "In8.Cu" "In9.Cu" "In10.Cu"
			)
			(hatch none 0.5)
			(connect_pads
				(clearance 0)
			)
			(min_thickness 0.25)
			(keepout
				(tracks not_allowed)
				(vias allowed)
				(pads allowed)
				(copperpour not_allowed)
				(footprints allowed)
			)
			(placement
				(enabled no)
				(sheetname "")
			)
			(fill
				(thermal_gap 0.5)
				(thermal_bridge_width 0.5)
				(island_removal_mode 0)
			)
			(polygon
				(pts
					(arc
						(start 95.583756 -1.138174)
						(mid 93.729556 -1.138174)
						(end 95.583756 -1.138174)
					)
				)
			)
		)
		(zone
			(layers "F.Cu" "B.Cu" "In1.Cu" "In2.Cu" "In3.Cu" "In4.Cu" "In5.Cu" "In6.Cu"
				"In7.Cu" "In8.Cu" "In9.Cu" "In10.Cu"
			)
			(hatch none 0.5)
			(connect_pads
				(clearance 0)
			)
			(min_thickness 0.25)
			(keepout
				(tracks not_allowed)
				(vias allowed)
				(pads allowed)
				(copperpour not_allowed)
				(footprints allowed)
			)
			(placement
				(enabled no)
				(sheetname "")
			)
			(fill
				(thermal_gap 0.5)
				(thermal_bridge_width 0.5)
				(island_removal_mode 0)
			)
			(polygon
				(pts
					(arc
						(start 98.123756 -7.488174)
						(mid 96.269556 -7.488174)
						(end 98.123756 -7.488174)
					)
				)
			)
		)
		(zone
			(layers "F.Cu" "B.Cu" "In1.Cu" "In2.Cu" "In3.Cu" "In4.Cu" "In5.Cu" "In6.Cu"
				"In7.Cu" "In8.Cu" "In9.Cu" "In10.Cu"
			)
			(hatch none 0.5)
			(connect_pads
				(clearance 0)
			)
			(min_thickness 0.25)
			(keepout
				(tracks not_allowed)
				(vias allowed)
				(pads allowed)
				(copperpour not_allowed)
				(footprints allowed)
			)
			(placement
				(enabled no)
				(sheetname "")
			)
			(fill
				(thermal_gap 0.5)
				(thermal_bridge_width 0.5)
				(island_removal_mode 0)
			)
			(polygon
				(pts
					(arc
						(start 98.123756 -1.138174)
						(mid 96.269556 -1.138174)
						(end 98.123756 -1.138174)
					)
				)
			)
		)
	)
)
